(kicad_pcb
	(version 20260206)
	(generator "pcbnew")
	(generator_version "10.0")
	(general
		(thickness 1.6)
		(legacy_teardrops no)
	)
	(paper "A4")
	(title_block
		(title "peb — Lightning_PEB_BRD.brd")
		(comment 1 "Lightning (Wiwynn / Facebook NVMe JBOF) / footprints 1475-1481 of 2563")
	)
	(layers
		(0 "F.Cu" signal "TOP")
		(4 "In1.Cu" signal "L2GND")
		(6 "In2.Cu" signal "L3")
		(8 "In3.Cu" signal "L4VCC")
		(10 "In4.Cu" signal "L5VCC")
		(12 "In5.Cu" signal "L6")
		(14 "In6.Cu" signal "L7GND")
		(2 "B.Cu" signal "BOTTOM")
		(9 "F.Adhes" user "F.Adhesive")
		(11 "B.Adhes" user "B.Adhesive")
		(13 "F.Paste" user "Package Geometry/Pastemask Top")
		(15 "B.Paste" user "Package Geometry/Pastemask Bottom")
		(5 "F.SilkS" user "Ref Des/Silkscreen Top")
		(7 "B.SilkS" user "Ref Des/Silkscreen Bottom")
		(1 "F.Mask" user "Board Geometry/Soldermask Top")
		(3 "B.Mask" user "Board Geometry/Soldermask Bottom")
		(17 "Dwgs.User" user "User.Drawings")
		(19 "Cmts.User" user "User.Comments")
		(21 "Eco1.User" user "User.Eco1")
		(23 "Eco2.User" user "User.Eco2")
		(25 "Edge.Cuts" user "Board Geometry/Outline")
		(27 "Margin" user)
		(31 "F.CrtYd" user "Package Geometry/Place Bound Top")
		(29 "B.CrtYd" user "Package Geometry/Place Bound Bottom")
		(35 "F.Fab" user "Ref Des/Assembly Top")
		(33 "B.Fab" user "Ref Des/Assembly Bottom")
	)
	(footprint ""
		(layer "F.Cu")
		(at 51.9684 -63.754 90)
		(property "Reference" "R501"
			(at 0 0 90)
			(layer "F.SilkS")
			(hide yes)
			(effects
				(font
					(size 1.27 1.27)
				)
			)
		)
		(property "Value" "3K3R2F-2-GP"
			(at 0.064008 -3.993896 90)
			(unlocked yes)
			(layer "F.Fab")
			(hide yes)
			(effects
				(font
					(size 1.016 1.016)
					(thickness 0.1524)
				)
			)
		)
		(property "Device Type" "R402H16"
			(at 0.064008 -5.517896 90)
			(unlocked yes)
			(layer "F.Fab")
			(hide yes)
			(effects
				(font
					(size 1.016 1.016)
					(thickness 0.1524)
				)
			)
		)
		(duplicate_pad_numbers_are_jumpers no)
		(fp_line
			(start 0.508 -0.9398)
			(end -0.508 -0.9398)
			(stroke
				(width 0.1524)
				(type default)
			)
			(layer "F.SilkS")
		)
		(fp_line
			(start -0.508 -0.9398)
			(end -0.508 0.9398)
			(stroke
				(width 0.1524)
				(type default)
			)
			(layer "F.SilkS")
		)
		(fp_rect
			(start -0.508 0.9398)
			(end 0.508 -0.9398)
			(stroke
				(width 0)
				(type default)
			)
			(fill no)
			(layer "F.CrtYd")
		)
		(fp_rect
			(start -0.508 0.9398)
			(end 0.508 -0.9398)
			(stroke
				(width 0)
				(type default)
			)
			(fill no)
			(layer "F.Fab")
		)
		(pad "1" smd custom
			(at 0 -0.4445 90)
			(size 0.1397 0.1397)
			(layers "F.Cu" "F.Mask" "F.Paste")
			(net "P3V3_STBY")
			(options
				(clearance outline)
				(anchor circle)
			)
			(primitives
				(gr_poly
					(pts
						(arc
							(start -0.1778 -0.2794)
							(mid -0.249642 -0.249642)
							(end -0.2794 -0.1778)
						)
						(arc
							(start -0.2794 0.1778)
							(mid -0.249642 0.249642)
							(end -0.1778 0.2794)
						)
						(arc
							(start 0.1778 0.2794)
							(mid 0.249642 0.249642)
							(end 0.2794 0.1778)
						)
						(arc
							(start 0.2794 -0.1778)
							(mid 0.249642 -0.249642)
							(end 0.1778 -0.2794)
						)
					)
					(width 0)
					(fill yes)
				)
			)
		)
		(pad "2" smd custom
			(at 0 0.4445 90)
			(size 0.1397 0.1397)
			(layers "F.Cu" "F.Mask" "F.Paste")
			(net "NVM_SO_R")
			(options
				(clearance outline)
				(anchor circle)
			)
			(primitives
				(gr_poly
					(pts
						(arc
							(start -0.1778 -0.2794)
							(mid -0.249642 -0.249642)
							(end -0.2794 -0.1778)
						)
						(arc
							(start -0.2794 0.1778)
							(mid -0.249642 0.249642)
							(end -0.1778 0.2794)
						)
						(arc
							(start 0.1778 0.2794)
							(mid 0.249642 0.249642)
							(end 0.2794 0.1778)
						)
						(arc
							(start 0.2794 -0.1778)
							(mid 0.249642 -0.249642)
							(end 0.1778 -0.2794)
						)
					)
					(width 0)
					(fill yes)
				)
			)
		)
	)
	(footprint ""
		(layer "F.Cu")
		(at 192.405 -30.1752 -90)
		(property "Reference" "R90"
			(at 0 0 270)
			(layer "F.SilkS")
			(hide yes)
			(effects
				(font
					(size 1.27 1.27)
				)
			)
		)
		(property "Value" "0R2J-2-GP"
			(at 0.064008 -3.993896 270)
			(unlocked yes)
			(layer "F.Fab")
			(hide yes)
			(effects
				(font
					(size 1.016 1.016)
					(thickness 0.1524)
				)
			)
		)
		(property "Device Type" "R402H16"
			(at 0.064008 -5.517896 270)
			(unlocked yes)
			(layer "F.Fab")
			(hide yes)
			(effects
				(font
					(size 1.016 1.016)
					(thickness 0.1524)
				)
			)
		)
		(duplicate_pad_numbers_are_jumpers no)
		(fp_line
			(start -0.508 -0.9398)
			(end -0.508 0.9398)
			(stroke
				(width 0.1524)
				(type default)
			)
			(layer "F.SilkS")
		)
		(fp_line
			(start 0.508 -0.9398)
			(end -0.508 -0.9398)
			(stroke
				(width 0.1524)
				(type default)
			)
			(layer "F.SilkS")
		)
		(fp_rect
			(start -0.508 0.9398)
			(end 0.508 -0.9398)
			(stroke
				(width 0)
				(type default)
			)
			(fill no)
			(layer "F.CrtYd")
		)
		(fp_rect
			(start -0.508 0.9398)
			(end 0.508 -0.9398)
			(stroke
				(width 0)
				(type default)
			)
			(fill no)
			(layer "F.Fab")
		)
		(pad "1" smd custom
			(at 0 -0.4445 270)
			(size 0.1397 0.1397)
			(layers "F.Cu" "F.Mask" "F.Paste")
			(net "U55_P0")
			(options
				(clearance outline)
				(anchor circle)
			)
			(primitives
				(gr_poly
					(pts
						(arc
							(start -0.1778 -0.2794)
							(mid -0.249642 -0.249642)
							(end -0.2794 -0.1778)
						)
						(arc
							(start -0.2794 0.1778)
							(mid -0.249642 0.249642)
							(end -0.1778 0.2794)
						)
						(arc
							(start 0.1778 0.2794)
							(mid 0.249642 0.249642)
							(end 0.2794 0.1778)
						)
						(arc
							(start 0.2794 -0.1778)
							(mid 0.249642 -0.249642)
							(end 0.1778 -0.2794)
						)
					)
					(width 0)
					(fill yes)
				)
			)
		)
		(pad "2" smd custom
			(at 0 0.4445 270)
			(size 0.1397 0.1397)
			(layers "F.Cu" "F.Mask" "F.Paste")
			(net "HOST_I2C_RESET_N")
			(options
				(clearance outline)
				(anchor circle)
			)
			(primitives
				(gr_poly
					(pts
						(arc
							(start -0.1778 -0.2794)
							(mid -0.249642 -0.249642)
							(end -0.2794 -0.1778)
						)
						(arc
							(start -0.2794 0.1778)
							(mid -0.249642 0.249642)
							(end -0.1778 0.2794)
						)
						(arc
							(start 0.1778 0.2794)
							(mid 0.249642 0.249642)
							(end 0.2794 0.1778)
						)
						(arc
							(start 0.2794 -0.1778)
							(mid 0.249642 -0.249642)
							(end 0.1778 -0.2794)
						)
					)
					(width 0)
					(fill yes)
				)
			)
		)
	)
	(footprint ""
		(layer "F.Cu")
		(at 329.565 -99.568 180)
		(property "Reference" "R4169"
			(at 0 0 180)
			(layer "F.SilkS")
			(hide yes)
			(effects
				(font
					(size 1.27 1.27)
				)
			)
		)
		(property "Value" "4K7R2F-GP"
			(at 0.064008 -3.993896 180)
			(unlocked yes)
			(layer "F.Fab")
			(hide yes)
			(effects
				(font
					(size 1.016 1.016)
					(thickness 0.1524)
				)
			)
		)
		(property "Device Type" "R402H16"
			(at 0.064008 -5.517896 180)
			(unlocked yes)
			(layer "F.Fab")
			(hide yes)
			(effects
				(font
					(size 1.016 1.016)
					(thickness 0.1524)
				)
			)
		)
		(duplicate_pad_numbers_are_jumpers no)
		(fp_line
			(start 0.508 -0.9398)
			(end -0.508 -0.9398)
			(stroke
				(width 0.1524)
				(type default)
			)
			(layer "F.SilkS")
		)
		(fp_line
			(start -0.508 -0.9398)
			(end -0.508 0.9398)
			(stroke
				(width 0.1524)
				(type default)
			)
			(layer "F.SilkS")
		)
		(fp_rect
			(start -0.508 0.9398)
			(end 0.508 -0.9398)
			(stroke
				(width 0)
				(type default)
			)
			(fill no)
			(layer "F.CrtYd")
		)
		(fp_rect
			(start -0.508 0.9398)
			(end 0.508 -0.9398)
			(stroke
				(width 0)
				(type default)
			)
			(fill no)
			(layer "F.Fab")
		)
		(pad "1" smd custom
			(at 0 -0.4445 180)
			(size 0.1397 0.1397)
			(layers "F.Cu" "F.Mask" "F.Paste")
			(net "VS3_LED")
			(options
				(clearance outline)
				(anchor circle)
			)
			(primitives
				(gr_poly
					(pts
						(arc
							(start -0.1778 -0.2794)
							(mid -0.249642 -0.249642)
							(end -0.2794 -0.1778)
						)
						(arc
							(start -0.2794 0.1778)
							(mid -0.249642 0.249642)
							(end -0.1778 0.2794)
						)
						(arc
							(start 0.1778 0.2794)
							(mid 0.249642 0.249642)
							(end 0.2794 0.1778)
						)
						(arc
							(start 0.2794 -0.1778)
							(mid 0.249642 -0.249642)
							(end 0.1778 -0.2794)
						)
					)
					(width 0)
					(fill yes)
				)
			)
		)
		(pad "2" smd custom
			(at 0 0.4445 180)
			(size 0.1397 0.1397)
			(layers "F.Cu" "F.Mask" "F.Paste")
			(net "P3V3_STBY")
			(options
				(clearance outline)
				(anchor circle)
			)
			(primitives
				(gr_poly
					(pts
						(arc
							(start -0.1778 -0.2794)
							(mid -0.249642 -0.249642)
							(end -0.2794 -0.1778)
						)
						(arc
							(start -0.2794 0.1778)
							(mid -0.249642 0.249642)
							(end -0.1778 0.2794)
						)
						(arc
							(start 0.1778 0.2794)
							(mid 0.249642 0.249642)
							(end 0.2794 0.1778)
						)
						(arc
							(start 0.2794 -0.1778)
							(mid 0.249642 -0.249642)
							(end 0.1778 -0.2794)
						)
					)
					(width 0)
					(fill yes)
				)
			)
		)
	)
	(footprint ""
		(layer "F.Cu")
		(at 329.819 -86.487)
		(property "Reference" "R4176"
			(at 0 0 0)
			(layer "F.SilkS")
			(hide yes)
			(effects
				(font
					(size 1.27 1.27)
				)
			)
		)
		(property "Value" "4K7R2F-GP"
			(at 0.064008 -3.993896 0)
			(unlocked yes)
			(layer "F.Fab")
			(hide yes)
			(effects
				(font
					(size 1.016 1.016)
					(thickness 0.1524)
				)
			)
		)
		(property "Device Type" "R402H16"
			(at 0.064008 -5.517896 0)
			(unlocked yes)
			(layer "F.Fab")
			(hide yes)
			(effects
				(font
					(size 1.016 1.016)
					(thickness 0.1524)
				)
			)
		)
		(duplicate_pad_numbers_are_jumpers no)
		(fp_line
			(start -0.508 -0.9398)
			(end -0.508 0.9398)
			(stroke
				(width 0.1524)
				(type default)
			)
			(layer "F.SilkS")
		)
		(fp_line
			(start 0.508 -0.9398)
			(end -0.508 -0.9398)
			(stroke
				(width 0.1524)
				(type default)
			)
			(layer "F.SilkS")
		)
		(fp_rect
			(start -0.508 0.9398)
			(end 0.508 -0.9398)
			(stroke
				(width 0)
				(type default)
			)
			(fill no)
			(layer "F.CrtYd")
		)
		(fp_rect
			(start -0.508 0.9398)
			(end 0.508 -0.9398)
			(stroke
				(width 0)
				(type default)
			)
			(fill no)
			(layer "F.Fab")
		)
		(pad "1" smd custom
			(at 0 -0.4445)
			(size 0.1397 0.1397)
			(layers "F.Cu" "F.Mask" "F.Paste")
			(net "UPLINK7")
			(options
				(clearance outline)
				(anchor circle)
			)
			(primitives
				(gr_poly
					(pts
						(arc
							(start -0.1778 -0.2794)
							(mid -0.249642 -0.249642)
							(end -0.2794 -0.1778)
						)
						(arc
							(start -0.2794 0.1778)
							(mid -0.249642 0.249642)
							(end -0.1778 0.2794)
						)
						(arc
							(start 0.1778 0.2794)
							(mid 0.249642 0.249642)
							(end 0.2794 0.1778)
						)
						(arc
							(start 0.2794 -0.1778)
							(mid 0.249642 -0.249642)
							(end 0.1778 -0.2794)
						)
					)
					(width 0)
					(fill yes)
				)
			)
		)
		(pad "2" smd custom
			(at 0 0.4445)
			(size 0.1397 0.1397)
			(layers "F.Cu" "F.Mask" "F.Paste")
			(net "P3V3_STBY")
			(options
				(clearance outline)
				(anchor circle)
			)
			(primitives
				(gr_poly
					(pts
						(arc
							(start -0.1778 -0.2794)
							(mid -0.249642 -0.249642)
							(end -0.2794 -0.1778)
						)
						(arc
							(start -0.2794 0.1778)
							(mid -0.249642 0.249642)
							(end -0.1778 0.2794)
						)
						(arc
							(start 0.1778 0.2794)
							(mid 0.249642 0.249642)
							(end 0.2794 0.1778)
						)
						(arc
							(start 0.2794 -0.1778)
							(mid 0.249642 -0.249642)
							(end 0.1778 -0.2794)
						)
					)
					(width 0)
					(fill yes)
				)
			)
		)
	)
	(footprint ""
		(layer "F.Cu")
		(at 21.0058 -134.4422 -90)
		(property "Reference" "R367"
			(at 0 0 270)
			(layer "F.SilkS")
			(hide yes)
			(effects
				(font
					(size 1.27 1.27)
				)
			)
		)
		(property "Value" "3K3R2F-2-GP"
			(at 0.064008 -3.993896 270)
			(unlocked yes)
			(layer "F.Fab")
			(hide yes)
			(effects
				(font
					(size 1.016 1.016)
					(thickness 0.1524)
				)
			)
		)
		(property "Device Type" "R402H16"
			(at 0.064008 -5.517896 270)
			(unlocked yes)
			(layer "F.Fab")
			(hide yes)
			(effects
				(font
					(size 1.016 1.016)
					(thickness 0.1524)
				)
			)
		)
		(duplicate_pad_numbers_are_jumpers no)
		(fp_line
			(start -0.508 -0.9398)
			(end -0.508 0.9398)
			(stroke
				(width 0.1524)
				(type default)
			)
			(layer "F.SilkS")
		)
		(fp_line
			(start 0.508 -0.9398)
			(end -0.508 -0.9398)
			(stroke
				(width 0.1524)
				(type default)
			)
			(layer "F.SilkS")
		)
		(fp_rect
			(start -0.508 0.9398)
			(end 0.508 -0.9398)
			(stroke
				(width 0)
				(type default)
			)
			(fill no)
			(layer "F.CrtYd")
		)
		(fp_rect
			(start -0.508 0.9398)
			(end 0.508 -0.9398)
			(stroke
				(width 0)
				(type default)
			)
			(fill no)
			(layer "F.Fab")
		)
		(pad "1" smd custom
			(at 0 -0.4445 270)
			(size 0.1397 0.1397)
			(layers "F.Cu" "F.Mask" "F.Paste")
			(net "P3V3_STBY")
			(options
				(clearance outline)
				(anchor circle)
			)
			(primitives
				(gr_poly
					(pts
						(arc
							(start -0.1778 -0.2794)
							(mid -0.249642 -0.249642)
							(end -0.2794 -0.1778)
						)
						(arc
							(start -0.2794 0.1778)
							(mid -0.249642 0.249642)
							(end -0.1778 0.2794)
						)
						(arc
							(start 0.1778 0.2794)
							(mid 0.249642 0.249642)
							(end 0.2794 0.1778)
						)
						(arc
							(start 0.2794 -0.1778)
							(mid 0.249642 -0.249642)
							(end 0.1778 -0.2794)
						)
					)
					(width 0)
					(fill yes)
				)
			)
		)
		(pad "2" smd custom
			(at 0 0.4445 270)
			(size 0.1397 0.1397)
			(layers "F.Cu" "F.Mask" "F.Paste")
			(net "ROMA7")
			(options
				(clearance outline)
				(anchor circle)
			)
			(primitives
				(gr_poly
					(pts
						(arc
							(start -0.1778 -0.2794)
							(mid -0.249642 -0.249642)
							(end -0.2794 -0.1778)
						)
						(arc
							(start -0.2794 0.1778)
							(mid -0.249642 0.249642)
							(end -0.1778 0.2794)
						)
						(arc
							(start 0.1778 0.2794)
							(mid 0.249642 0.249642)
							(end 0.2794 0.1778)
						)
						(arc
							(start 0.2794 -0.1778)
							(mid 0.249642 -0.249642)
							(end 0.1778 -0.2794)
						)
					)
					(width 0)
					(fill yes)
				)
			)
		)
	)
	(footprint ""
		(layer "F.Cu")
		(at 158.242 -95.9104)
		(property "Reference" "R100"
			(at 0 0 0)
			(layer "F.SilkS")
			(hide yes)
			(effects
				(font
					(size 1.27 1.27)
				)
			)
		)
		(property "Value" "10KR2F-2-GP"
			(at 0.064008 -3.993896 0)
			(unlocked yes)
			(layer "F.Fab")
			(hide yes)
			(effects
				(font
					(size 1.016 1.016)
					(thickness 0.1524)
				)
			)
		)
		(property "Device Type" "R402H16"
			(at 0.064008 -5.517896 0)
			(unlocked yes)
			(layer "F.Fab")
			(hide yes)
			(effects
				(font
					(size 1.016 1.016)
					(thickness 0.1524)
				)
			)
		)
		(duplicate_pad_numbers_are_jumpers no)
		(fp_line
			(start -0.508 -0.9398)
			(end -0.508 0.9398)
			(stroke
				(width 0.1524)
				(type default)
			)
			(layer "F.SilkS")
		)
		(fp_line
			(start 0.508 -0.9398)
			(end -0.508 -0.9398)
			(stroke
				(width 0.1524)
				(type default)
			)
			(layer "F.SilkS")
		)
		(fp_rect
			(start -0.508 0.9398)
			(end 0.508 -0.9398)
			(stroke
				(width 0)
				(type default)
			)
			(fill no)
			(layer "F.CrtYd")
		)
		(fp_rect
			(start -0.508 0.9398)
			(end 0.508 -0.9398)
			(stroke
				(width 0)
				(type default)
			)
			(fill no)
			(layer "F.Fab")
		)
		(pad "1" smd custom
			(at 0 -0.4445)
			(size 0.1397 0.1397)
			(layers "F.Cu" "F.Mask" "F.Paste")
			(net "GND")
			(options
				(clearance outline)
				(anchor circle)
			)
			(primitives
				(gr_poly
					(pts
						(arc
							(start -0.1778 -0.2794)
							(mid -0.249642 -0.249642)
							(end -0.2794 -0.1778)
						)
						(arc
							(start -0.2794 0.1778)
							(mid -0.249642 0.249642)
							(end -0.1778 0.2794)
						)
						(arc
							(start 0.1778 0.2794)
							(mid 0.249642 0.249642)
							(end 0.2794 0.1778)
						)
						(arc
							(start 0.2794 -0.1778)
							(mid 0.249642 -0.249642)
							(end 0.1778 -0.2794)
						)
					)
					(width 0)
					(fill yes)
				)
			)
		)
		(pad "2" smd custom
			(at 0 0.4445)
			(size 0.1397 0.1397)
			(layers "F.Cu" "F.Mask" "F.Paste")
			(net "CLKGEN_PWGD")
			(options
				(clearance outline)
				(anchor circle)
			)
			(primitives
				(gr_poly
					(pts
						(arc
							(start -0.1778 -0.2794)
							(mid -0.249642 -0.249642)
							(end -0.2794 -0.1778)
						)
						(arc
							(start -0.2794 0.1778)
							(mid -0.249642 0.249642)
							(end -0.1778 0.2794)
						)
						(arc
							(start 0.1778 0.2794)
							(mid 0.249642 0.249642)
							(end 0.2794 0.1778)
						)
						(arc
							(start 0.2794 -0.1778)
							(mid 0.249642 -0.249642)
							(end 0.1778 -0.2794)
						)
					)
					(width 0)
					(fill yes)
				)
			)
		)
	)
	(footprint ""
		(layer "F.Cu")
		(at 74.950066 -195.6689 180)
		(property "Reference" "R7945"
			(at 0 0 180)
			(layer "F.SilkS")
			(hide yes)
			(effects
				(font
					(size 1.27 1.27)
				)
			)
		)
		(property "Value" "0R2J-2-GP"
			(at 0.064008 -3.993896 180)
			(unlocked yes)
			(layer "F.Fab")
			(hide yes)
			(effects
				(font
					(size 1.016 1.016)
					(thickness 0.1524)
				)
			)
		)
		(property "Device Type" "R402H16"
			(at 0.064008 -5.517896 180)
			(unlocked yes)
			(layer "F.Fab")
			(hide yes)
			(effects
				(font
					(size 1.016 1.016)
					(thickness 0.1524)
				)
			)
		)
		(duplicate_pad_numbers_are_jumpers no)
		(fp_line
			(start 0.508 -0.9398)
			(end -0.508 -0.9398)
			(stroke
				(width 0.1524)
				(type default)
			)
			(layer "F.SilkS")
		)
		(fp_line
			(start -0.508 -0.9398)
			(end -0.508 0.9398)
			(stroke
				(width 0.1524)
				(type default)
			)
			(layer "F.SilkS")
		)
		(fp_rect
			(start -0.508 0.9398)
			(end 0.508 -0.9398)
			(stroke
				(width 0)
				(type default)
			)
			(fill no)
			(layer "F.CrtYd")
		)
		(fp_rect
			(start -0.508 0.9398)
			(end 0.508 -0.9398)
			(stroke
				(width 0)
				(type default)
			)
			(fill no)
			(layer "F.Fab")
		)
		(pad "1" smd custom
			(at 0 -0.4445 180)
			(size 0.1397 0.1397)
			(layers "F.Cu" "F.Mask" "F.Paste")
			(net "SSD_ATNLED#11")
			(options
				(clearance outline)
				(anchor circle)
			)
			(primitives
				(gr_poly
					(pts
						(arc
							(start -0.1778 -0.2794)
							(mid -0.249642 -0.249642)
							(end -0.2794 -0.1778)
						)
						(arc
							(start -0.2794 0.1778)
							(mid -0.249642 0.249642)
							(end -0.1778 0.2794)
						)
						(arc
							(start 0.1778 0.2794)
							(mid 0.249642 0.249642)
							(end 0.2794 0.1778)
						)
						(arc
							(start 0.2794 -0.1778)
							(mid 0.249642 -0.249642)
							(end 0.1778 -0.2794)
						)
					)
					(width 0)
					(fill yes)
				)
			)
		)
		(pad "2" smd custom
			(at 0 0.4445 180)
			(size 0.1397 0.1397)
			(layers "F.Cu" "F.Mask" "F.Paste")
			(net "SSD_ATNLED#11_R")
			(options
				(clearance outline)
				(anchor circle)
			)
			(primitives
				(gr_poly
					(pts
						(arc
							(start -0.1778 -0.2794)
							(mid -0.249642 -0.249642)
							(end -0.2794 -0.1778)
						)
						(arc
							(start -0.2794 0.1778)
							(mid -0.249642 0.249642)
							(end -0.1778 0.2794)
						)
						(arc
							(start 0.1778 0.2794)
							(mid 0.249642 0.249642)
							(end 0.2794 0.1778)
						)
						(arc
							(start 0.2794 -0.1778)
							(mid 0.249642 -0.249642)
							(end 0.1778 -0.2794)
						)
					)
					(width 0)
					(fill yes)
				)
			)
		)
	)
)
